(kicad_pcb
	(version 20260206)
	(generator "pcbnew")
	(generator_version "10.0")
	(general
		(thickness 1.6)
		(legacy_teardrops no)
	)
	(paper "A4")
	(title_block
		(title "baseboard — 13948-1b.1110WZS1818.brd")
		(comment 1 "Honey Badger (Wiwynn) / footprints 71-77 of 2523")
	)
	(layers
		(0 "F.Cu" signal "TOP")
		(4 "In1.Cu" signal "L2GND")
		(6 "In2.Cu" signal "L3")
		(8 "In3.Cu" signal "L4VCC")
		(10 "In4.Cu" signal "L5VCC")
		(12 "In5.Cu" signal "L6")
		(14 "In6.Cu" signal "L7GND")
		(2 "B.Cu" signal "BOTTOM")
		(9 "F.Adhes" user "F.Adhesive")
		(11 "B.Adhes" user "B.Adhesive")
		(13 "F.Paste" user "Package Geometry/Pastemask Top")
		(15 "B.Paste" user "Package Geometry/Pastemask Bottom")
		(5 "F.SilkS" user "Ref Des/Silkscreen Top")
		(7 "B.SilkS" user "Ref Des/Silkscreen Bottom")
		(1 "F.Mask" user "Board Geometry/Soldermask Top")
		(3 "B.Mask" user "Board Geometry/Soldermask Bottom")
		(17 "Dwgs.User" user "User.Drawings")
		(19 "Cmts.User" user "User.Comments")
		(21 "Eco1.User" user "User.Eco1")
		(23 "Eco2.User" user "User.Eco2")
		(25 "Edge.Cuts" user "Board Geometry/Outline")
		(27 "Margin" user)
		(31 "F.CrtYd" user "Package Geometry/Place Bound Top")
		(29 "B.CrtYd" user "Package Geometry/Place Bound Bottom")
		(35 "F.Fab" user "Ref Des/Assembly Top")
		(33 "B.Fab" user "Ref Des/Assembly Bottom")
	)
	(footprint ""
		(layer "F.Cu")
		(at 45.593 -219.456)
		(property "Reference" "R9021"
			(at 0 0 0)
			(layer "F.SilkS")
			(hide yes)
			(effects
				(font
					(size 1.27 1.27)
				)
			)
		)
		(property "Value" "42K2R2F-L-GP"
			(at 0.064008 -3.993896 0)
			(unlocked yes)
			(layer "F.Fab")
			(hide yes)
			(effects
				(font
					(size 1.016 1.016)
					(thickness 0.1524)
				)
			)
		)
		(property "Device Type" "R402H16"
			(at 0.064008 -5.517896 0)
			(unlocked yes)
			(layer "F.Fab")
			(hide yes)
			(effects
				(font
					(size 1.016 1.016)
					(thickness 0.1524)
				)
			)
		)
		(duplicate_pad_numbers_are_jumpers no)
		(fp_line
			(start -0.508 -0.9398)
			(end -0.508 0.9398)
			(stroke
				(width 0.1524)
				(type default)
			)
			(layer "F.SilkS")
		)
		(fp_line
			(start 0.508 -0.9398)
			(end -0.508 -0.9398)
			(stroke
				(width 0.1524)
				(type default)
			)
			(layer "F.SilkS")
		)
		(fp_rect
			(start -0.508 0.9398)
			(end 0.508 -0.9398)
			(stroke
				(width 0)
				(type default)
			)
			(fill no)
			(layer "F.CrtYd")
		)
		(fp_rect
			(start -0.508 0.9398)
			(end 0.508 -0.9398)
			(stroke
				(width 0)
				(type default)
			)
			(fill no)
			(layer "F.Fab")
		)
		(pad "1" smd custom
			(at 0 -0.4445)
			(size 0.1397 0.1397)
			(layers "F.Cu" "F.Mask" "F.Paste")
			(net "MB0_ISET_R")
			(options
				(clearance outline)
				(anchor circle)
			)
			(primitives
				(gr_poly
					(pts
						(arc
							(start -0.1778 -0.2794)
							(mid -0.249642 -0.249642)
							(end -0.2794 -0.1778)
						)
						(arc
							(start -0.2794 0.1778)
							(mid -0.249642 0.249642)
							(end -0.1778 0.2794)
						)
						(arc
							(start 0.1778 0.2794)
							(mid 0.249642 0.249642)
							(end 0.2794 0.1778)
						)
						(arc
							(start 0.2794 -0.1778)
							(mid 0.249642 -0.249642)
							(end 0.1778 -0.2794)
						)
					)
					(width 0)
					(fill yes)
				)
			)
		)
		(pad "2" smd custom
			(at 0 0.4445)
			(size 0.1397 0.1397)
			(layers "F.Cu" "F.Mask" "F.Paste")
			(net "AGND_CURRENT_MON")
			(options
				(clearance outline)
				(anchor circle)
			)
			(primitives
				(gr_poly
					(pts
						(arc
							(start -0.1778 -0.2794)
							(mid -0.249642 -0.249642)
							(end -0.2794 -0.1778)
						)
						(arc
							(start -0.2794 0.1778)
							(mid -0.249642 0.249642)
							(end -0.1778 0.2794)
						)
						(arc
							(start 0.1778 0.2794)
							(mid 0.249642 0.249642)
							(end 0.2794 0.1778)
						)
						(arc
							(start 0.2794 -0.1778)
							(mid 0.249642 -0.249642)
							(end 0.1778 -0.2794)
						)
					)
					(width 0)
					(fill yes)
				)
			)
		)
	)
	(footprint ""
		(layer "F.Cu")
		(at 274.193 -177.673 90)
		(property "Reference" "R361"
			(at 0 0 90)
			(layer "F.SilkS")
			(hide yes)
			(effects
				(font
					(size 1.27 1.27)
				)
			)
		)
		(property "Value" "3K3R2F-2-GP"
			(at 0.064008 -3.993896 90)
			(unlocked yes)
			(layer "F.Fab")
			(hide yes)
			(effects
				(font
					(size 1.016 1.016)
					(thickness 0.1524)
				)
			)
		)
		(property "Device Type" "R402H16"
			(at 0.064008 -5.517896 90)
			(unlocked yes)
			(layer "F.Fab")
			(hide yes)
			(effects
				(font
					(size 1.016 1.016)
					(thickness 0.1524)
				)
			)
		)
		(duplicate_pad_numbers_are_jumpers no)
		(fp_line
			(start 0.508 -0.9398)
			(end -0.508 -0.9398)
			(stroke
				(width 0.1524)
				(type default)
			)
			(layer "F.SilkS")
		)
		(fp_line
			(start -0.508 -0.9398)
			(end -0.508 0.9398)
			(stroke
				(width 0.1524)
				(type default)
			)
			(layer "F.SilkS")
		)
		(fp_rect
			(start -0.508 0.9398)
			(end 0.508 -0.9398)
			(stroke
				(width 0)
				(type default)
			)
			(fill no)
			(layer "F.CrtYd")
		)
		(fp_rect
			(start -0.508 0.9398)
			(end 0.508 -0.9398)
			(stroke
				(width 0)
				(type default)
			)
			(fill no)
			(layer "F.Fab")
		)
		(pad "1" smd custom
			(at 0 -0.4445 90)
			(size 0.1397 0.1397)
			(layers "F.Cu" "F.Mask" "F.Paste")
			(net "P3V3_STBY")
			(options
				(clearance outline)
				(anchor circle)
			)
			(primitives
				(gr_poly
					(pts
						(arc
							(start -0.1778 -0.2794)
							(mid -0.249642 -0.249642)
							(end -0.2794 -0.1778)
						)
						(arc
							(start -0.2794 0.1778)
							(mid -0.249642 0.249642)
							(end -0.1778 0.2794)
						)
						(arc
							(start 0.1778 0.2794)
							(mid 0.249642 0.249642)
							(end 0.2794 0.1778)
						)
						(arc
							(start 0.2794 -0.1778)
							(mid 0.249642 -0.249642)
							(end 0.1778 -0.2794)
						)
					)
					(width 0)
					(fill yes)
				)
			)
		)
		(pad "2" smd custom
			(at 0 0.4445 90)
			(size 0.1397 0.1397)
			(layers "F.Cu" "F.Mask" "F.Paste")
			(net "ROMA21")
			(options
				(clearance outline)
				(anchor circle)
			)
			(primitives
				(gr_poly
					(pts
						(arc
							(start -0.1778 -0.2794)
							(mid -0.249642 -0.249642)
							(end -0.2794 -0.1778)
						)
						(arc
							(start -0.2794 0.1778)
							(mid -0.249642 0.249642)
							(end -0.1778 0.2794)
						)
						(arc
							(start 0.1778 0.2794)
							(mid 0.249642 0.249642)
							(end 0.2794 0.1778)
						)
						(arc
							(start 0.2794 -0.1778)
							(mid 0.249642 -0.249642)
							(end 0.1778 -0.2794)
						)
					)
					(width 0)
					(fill yes)
				)
			)
		)
	)
	(footprint ""
		(layer "F.Cu")
		(at 303.320958 -60.452 -90)
		(property "Reference" "R205"
			(at 0 0 270)
			(layer "F.SilkS")
			(hide yes)
			(effects
				(font
					(size 1.27 1.27)
				)
			)
		)
		(property "Value" "0R2J-2-GP"
			(at 0.064008 -3.993896 270)
			(unlocked yes)
			(layer "F.Fab")
			(hide yes)
			(effects
				(font
					(size 1.016 1.016)
					(thickness 0.1524)
				)
			)
		)
		(property "Device Type" "R402H16"
			(at 0.064008 -5.517896 270)
			(unlocked yes)
			(layer "F.Fab")
			(hide yes)
			(effects
				(font
					(size 1.016 1.016)
					(thickness 0.1524)
				)
			)
		)
		(duplicate_pad_numbers_are_jumpers no)
		(fp_line
			(start -0.508 -0.9398)
			(end -0.508 0.9398)
			(stroke
				(width 0.1524)
				(type default)
			)
			(layer "F.SilkS")
		)
		(fp_line
			(start 0.508 -0.9398)
			(end -0.508 -0.9398)
			(stroke
				(width 0.1524)
				(type default)
			)
			(layer "F.SilkS")
		)
		(fp_rect
			(start -0.508 0.9398)
			(end 0.508 -0.9398)
			(stroke
				(width 0)
				(type default)
			)
			(fill no)
			(layer "F.CrtYd")
		)
		(fp_rect
			(start -0.508 0.9398)
			(end 0.508 -0.9398)
			(stroke
				(width 0)
				(type default)
			)
			(fill no)
			(layer "F.Fab")
		)
		(pad "1" smd custom
			(at 0 -0.4445 270)
			(size 0.1397 0.1397)
			(layers "F.Cu" "F.Mask" "F.Paste")
			(net "SAS_I2C_C_10G_SCL")
			(options
				(clearance outline)
				(anchor circle)
			)
			(primitives
				(gr_poly
					(pts
						(arc
							(start -0.1778 -0.2794)
							(mid -0.249642 -0.249642)
							(end -0.2794 -0.1778)
						)
						(arc
							(start -0.2794 0.1778)
							(mid -0.249642 0.249642)
							(end -0.1778 0.2794)
						)
						(arc
							(start 0.1778 0.2794)
							(mid 0.249642 0.249642)
							(end 0.2794 0.1778)
						)
						(arc
							(start 0.2794 -0.1778)
							(mid 0.249642 -0.249642)
							(end 0.1778 -0.2794)
						)
					)
					(width 0)
					(fill yes)
				)
			)
		)
		(pad "2" smd custom
			(at 0 0.4445 270)
			(size 0.1397 0.1397)
			(layers "F.Cu" "F.Mask" "F.Paste")
			(net "BMC_10G_SCL_2")
			(options
				(clearance outline)
				(anchor circle)
			)
			(primitives
				(gr_poly
					(pts
						(arc
							(start -0.1778 -0.2794)
							(mid -0.249642 -0.249642)
							(end -0.2794 -0.1778)
						)
						(arc
							(start -0.2794 0.1778)
							(mid -0.249642 0.249642)
							(end -0.1778 0.2794)
						)
						(arc
							(start 0.1778 0.2794)
							(mid 0.249642 0.249642)
							(end 0.2794 0.1778)
						)
						(arc
							(start 0.2794 -0.1778)
							(mid 0.249642 -0.249642)
							(end 0.1778 -0.2794)
						)
					)
					(width 0)
					(fill yes)
				)
			)
		)
	)
	(footprint ""
		(layer "F.Cu")
		(at 35.052 -79.248 -90)
		(property "Reference" "R677"
			(at 0 0 270)
			(layer "F.SilkS")
			(hide yes)
			(effects
				(font
					(size 1.27 1.27)
				)
			)
		)
		(property "Value" "1KR2F-3-GP"
			(at 0.064008 -3.993896 270)
			(unlocked yes)
			(layer "F.Fab")
			(hide yes)
			(effects
				(font
					(size 1.016 1.016)
					(thickness 0.1524)
				)
			)
		)
		(property "Device Type" "R402H16"
			(at 0.064008 -5.517896 270)
			(unlocked yes)
			(layer "F.Fab")
			(hide yes)
			(effects
				(font
					(size 1.016 1.016)
					(thickness 0.1524)
				)
			)
		)
		(duplicate_pad_numbers_are_jumpers no)
		(fp_line
			(start -0.508 -0.9398)
			(end -0.508 0.9398)
			(stroke
				(width 0.1524)
				(type default)
			)
			(layer "F.SilkS")
		)
		(fp_line
			(start 0.508 -0.9398)
			(end -0.508 -0.9398)
			(stroke
				(width 0.1524)
				(type default)
			)
			(layer "F.SilkS")
		)
		(fp_rect
			(start -0.508 0.9398)
			(end 0.508 -0.9398)
			(stroke
				(width 0)
				(type default)
			)
			(fill no)
			(layer "F.CrtYd")
		)
		(fp_rect
			(start -0.508 0.9398)
			(end 0.508 -0.9398)
			(stroke
				(width 0)
				(type default)
			)
			(fill no)
			(layer "F.Fab")
		)
		(pad "1" smd custom
			(at 0 -0.4445 270)
			(size 0.1397 0.1397)
			(layers "F.Cu" "F.Mask" "F.Paste")
			(net "INTA_LED_BLUE_B")
			(options
				(clearance outline)
				(anchor circle)
			)
			(primitives
				(gr_poly
					(pts
						(arc
							(start -0.1778 -0.2794)
							(mid -0.249642 -0.249642)
							(end -0.2794 -0.1778)
						)
						(arc
							(start -0.2794 0.1778)
							(mid -0.249642 0.249642)
							(end -0.1778 0.2794)
						)
						(arc
							(start 0.1778 0.2794)
							(mid 0.249642 0.249642)
							(end 0.2794 0.1778)
						)
						(arc
							(start 0.2794 -0.1778)
							(mid 0.249642 -0.249642)
							(end 0.1778 -0.2794)
						)
					)
					(width 0)
					(fill yes)
				)
			)
		)
		(pad "2" smd custom
			(at 0 0.4445 270)
			(size 0.1397 0.1397)
			(layers "F.Cu" "F.Mask" "F.Paste")
			(net "GND")
			(options
				(clearance outline)
				(anchor circle)
			)
			(primitives
				(gr_poly
					(pts
						(arc
							(start -0.1778 -0.2794)
							(mid -0.249642 -0.249642)
							(end -0.2794 -0.1778)
						)
						(arc
							(start -0.2794 0.1778)
							(mid -0.249642 0.249642)
							(end -0.1778 0.2794)
						)
						(arc
							(start 0.1778 0.2794)
							(mid 0.249642 0.249642)
							(end 0.2794 0.1778)
						)
						(arc
							(start 0.2794 -0.1778)
							(mid 0.249642 -0.249642)
							(end 0.1778 -0.2794)
						)
					)
					(width 0)
					(fill yes)
				)
			)
		)
	)
	(footprint ""
		(layer "F.Cu")
		(at 14.928088 -202.185016)
		(property "Reference" "SR579"
			(at 0 0 0)
			(layer "F.SilkS")
			(hide yes)
			(effects
				(font
					(size 1.27 1.27)
				)
			)
		)
		(property "Value" "4K7R2F-GP"
			(at 0.064008 -3.993896 0)
			(unlocked yes)
			(layer "F.Fab")
			(hide yes)
			(effects
				(font
					(size 1.016 1.016)
					(thickness 0.1524)
				)
			)
		)
		(property "Device Type" "R402H16"
			(at 0.064008 -5.517896 0)
			(unlocked yes)
			(layer "F.Fab")
			(hide yes)
			(effects
				(font
					(size 1.016 1.016)
					(thickness 0.1524)
				)
			)
		)
		(duplicate_pad_numbers_are_jumpers no)
		(fp_line
			(start -0.508 -0.9398)
			(end -0.508 0.9398)
			(stroke
				(width 0.1524)
				(type default)
			)
			(layer "F.SilkS")
		)
		(fp_line
			(start 0.508 -0.9398)
			(end -0.508 -0.9398)
			(stroke
				(width 0.1524)
				(type default)
			)
			(layer "F.SilkS")
		)
		(fp_rect
			(start -0.508 0.9398)
			(end 0.508 -0.9398)
			(stroke
				(width 0)
				(type default)
			)
			(fill no)
			(layer "F.CrtYd")
		)
		(fp_rect
			(start -0.508 0.9398)
			(end 0.508 -0.9398)
			(stroke
				(width 0)
				(type default)
			)
			(fill no)
			(layer "F.Fab")
		)
		(pad "1" smd custom
			(at 0 -0.4445)
			(size 0.1397 0.1397)
			(layers "F.Cu" "F.Mask" "F.Paste")
			(net "BMC_I2C_SDA_10")
			(options
				(clearance outline)
				(anchor circle)
			)
			(primitives
				(gr_poly
					(pts
						(arc
							(start -0.1778 -0.2794)
							(mid -0.249642 -0.249642)
							(end -0.2794 -0.1778)
						)
						(arc
							(start -0.2794 0.1778)
							(mid -0.249642 0.249642)
							(end -0.1778 0.2794)
						)
						(arc
							(start 0.1778 0.2794)
							(mid 0.249642 0.249642)
							(end 0.2794 0.1778)
						)
						(arc
							(start 0.2794 -0.1778)
							(mid 0.249642 -0.249642)
							(end 0.1778 -0.2794)
						)
					)
					(width 0)
					(fill yes)
				)
			)
		)
		(pad "2" smd custom
			(at 0 0.4445)
			(size 0.1397 0.1397)
			(layers "F.Cu" "F.Mask" "F.Paste")
			(net "P3V3_STBY")
			(options
				(clearance outline)
				(anchor circle)
			)
			(primitives
				(gr_poly
					(pts
						(arc
							(start -0.1778 -0.2794)
							(mid -0.249642 -0.249642)
							(end -0.2794 -0.1778)
						)
						(arc
							(start -0.2794 0.1778)
							(mid -0.249642 0.249642)
							(end -0.1778 0.2794)
						)
						(arc
							(start 0.1778 0.2794)
							(mid 0.249642 0.249642)
							(end 0.2794 0.1778)
						)
						(arc
							(start 0.2794 -0.1778)
							(mid 0.249642 -0.249642)
							(end 0.1778 -0.2794)
						)
					)
					(width 0)
					(fill yes)
				)
			)
		)
	)
	(footprint ""
		(layer "F.Cu")
		(at 284.979872 -215.591136 180)
		(property "Reference" "PC87"
			(at 0 0 180)
			(layer "F.SilkS")
			(hide yes)
			(effects
				(font
					(size 1.27 1.27)
				)
			)
		)
		(property "Value" "SC470P50V2KX-3GP"
			(at 1.1811 -2.7051 180)
			(unlocked yes)
			(layer "F.Fab")
			(hide yes)
			(effects
				(font
					(size 1.016 1.016)
					(thickness 0.1524)
				)
			)
		)
		(property "Device Type" "C402H22"
			(at 1.1811 -4.2291 180)
			(unlocked yes)
			(layer "F.Fab")
			(hide yes)
			(effects
				(font
					(size 1.016 1.016)
					(thickness 0.1524)
				)
			)
		)
		(duplicate_pad_numbers_are_jumpers no)
		(fp_rect
			(start -0.4318 0.9525)
			(end 0.4318 -0.9525)
			(stroke
				(width 0)
				(type default)
			)
			(fill no)
			(layer "F.CrtYd")
		)
		(fp_rect
			(start -0.4318 0.9525)
			(end 0.4318 -0.9525)
			(stroke
				(width 0)
				(type default)
			)
			(fill no)
			(layer "F.Fab")
		)
		(pad "1" smd custom
			(at 0 -0.4445 180)
			(size 0.1524 0.1524)
			(layers "F.Cu" "F.Mask" "F.Paste")
			(net "GND")
			(options
				(clearance outline)
				(anchor circle)
			)
			(primitives
				(gr_poly
					(pts
						(arc
							(start 0.3048 -0.2032)
							(mid 0.275042 -0.275042)
							(end 0.2032 -0.3048)
						)
						(arc
							(start -0.2032 -0.3048)
							(mid -0.275042 -0.275042)
							(end -0.3048 -0.2032)
						)
						(arc
							(start -0.3048 0.2032)
							(mid -0.275042 0.275042)
							(end -0.2032 0.3048)
						)
						(arc
							(start 0.2032 0.3048)
							(mid 0.275042 0.275042)
							(end 0.3048 0.2032)
						)
					)
					(width 0)
					(fill yes)
				)
			)
		)
		(pad "2" smd custom
			(at 0 0.4445 180)
			(size 0.1524 0.1524)
			(layers "F.Cu" "F.Mask" "F.Paste")
			(net "TPS74801_1V53_STBY_SS")
			(options
				(clearance outline)
				(anchor circle)
			)
			(primitives
				(gr_poly
					(pts
						(arc
							(start 0.3048 -0.2032)
							(mid 0.275042 -0.275042)
							(end 0.2032 -0.3048)
						)
						(arc
							(start -0.2032 -0.3048)
							(mid -0.275042 -0.275042)
							(end -0.3048 -0.2032)
						)
						(arc
							(start -0.3048 0.2032)
							(mid -0.275042 0.275042)
							(end -0.2032 0.3048)
						)
						(arc
							(start 0.2032 0.3048)
							(mid 0.275042 0.275042)
							(end 0.3048 0.2032)
						)
					)
					(width 0)
					(fill yes)
				)
			)
		)
	)
	(footprint ""
		(layer "F.Cu")
		(at 179.33797 -67.183 180)
		(property "Reference" "C289"
			(at 0 0 180)
			(layer "F.SilkS")
			(hide yes)
			(effects
				(font
					(size 1.27 1.27)
				)
			)
		)
		(property "Value" "SCD1U25V2KX-2-GP"
			(at 1.1811 -2.7051 180)
			(unlocked yes)
			(layer "F.Fab")
			(hide yes)
			(effects
				(font
					(size 1.016 1.016)
					(thickness 0.1524)
				)
			)
		)
		(property "Device Type" "C402H22"
			(at 1.1811 -4.2291 180)
			(unlocked yes)
			(layer "F.Fab")
			(hide yes)
			(effects
				(font
					(size 1.016 1.016)
					(thickness 0.1524)
				)
			)
		)
		(duplicate_pad_numbers_are_jumpers no)
		(fp_rect
			(start -0.4318 0.9525)
			(end 0.4318 -0.9525)
			(stroke
				(width 0)
				(type default)
			)
			(fill no)
			(layer "F.CrtYd")
		)
		(fp_rect
			(start -0.4318 0.9525)
			(end 0.4318 -0.9525)
			(stroke
				(width 0)
				(type default)
			)
			(fill no)
			(layer "F.Fab")
		)
		(pad "1" smd custom
			(at 0 -0.4445 180)
			(size 0.1524 0.1524)
			(layers "F.Cu" "F.Mask" "F.Paste")
			(net "GND")
			(options
				(clearance outline)
				(anchor circle)
			)
			(primitives
				(gr_poly
					(pts
						(arc
							(start 0.3048 -0.2032)
							(mid 0.275042 -0.275042)
							(end 0.2032 -0.3048)
						)
						(arc
							(start -0.2032 -0.3048)
							(mid -0.275042 -0.275042)
							(end -0.3048 -0.2032)
						)
						(arc
							(start -0.3048 0.2032)
							(mid -0.275042 0.275042)
							(end -0.2032 0.3048)
						)
						(arc
							(start 0.2032 0.3048)
							(mid 0.275042 0.275042)
							(end 0.3048 0.2032)
						)
					)
					(width 0)
					(fill yes)
				)
			)
		)
		(pad "2" smd custom
			(at 0 0.4445 180)
			(size 0.1524 0.1524)
			(layers "F.Cu" "F.Mask" "F.Paste")
			(net "TP_MSB_B32_CPU_SATA_TX_N")
			(options
				(clearance outline)
				(anchor circle)
			)
			(primitives
				(gr_poly
					(pts
						(arc
							(start 0.3048 -0.2032)
							(mid 0.275042 -0.275042)
							(end 0.2032 -0.3048)
						)
						(arc
							(start -0.2032 -0.3048)
							(mid -0.275042 -0.275042)
							(end -0.3048 -0.2032)
						)
						(arc
							(start -0.3048 0.2032)
							(mid -0.275042 0.275042)
							(end -0.2032 0.3048)
						)
						(arc
							(start 0.2032 0.3048)
							(mid 0.275042 0.275042)
							(end 0.3048 0.2032)
						)
					)
					(width 0)
					(fill yes)
				)
			)
		)
	)
)
